# T6G (Grand Teton) — schematic netlist excerpt (pin names and nets, part order shuffled) for the footprints in the layout excerpt that follows; sources: Cadence DE-HDL packaged netlist, KiCad conversion of 04192023_DAF0TMB3IC0_F0TG_MB_C_brd_V02_OCP.brd

J28  SCONN288_DDR506112002KQ  IO  pkg DDR288S_1-1VXC  page 100
  VIN_BULK0  = P12V_MEM_CPU1
  RFU0  = NC
  VIN_MGMT  = P3V3_AUX
  HSCL  = I3C_SPD_DDRC_CPU1_SCL
  HSDA  = I3C_SPD_DDRC_CPU1_SDA
  VSS0  = GND
  DQ0_A  = M_C_CPU1_SA_DQ<0>
  VSS1  = GND
  DQ1_A  = M_C_CPU1_SA_DQ<1>
  VSS2  = GND
  DQS0_A_T  = M_C_CPU1_SA_DQS_DP<0>
  DQS0_A_C  = M_C_CPU1_SA_DQS_DN<0>
  VSS3  = GND
  DQ4_A  = M_C_CPU1_SA_DQ<4>
  VSS4  = GND
  DQ5_A  = M_C_CPU1_SA_DQ<5>
  VSS5  = GND
  DQ8_A  = M_C_CPU1_SA_DQ<8>
  VSS6  = GND
  DQ9_A  = M_C_CPU1_SA_DQ<9>
  VSS7  = GND
  DQS1_A_T  = M_C_CPU1_SA_DQS_DP<1>
  DQS1_A_C  = M_C_CPU1_SA_DQS_DN<1>
  VSS8  = GND
  DQ12_A  = M_C_CPU1_SA_DQ<12>
  VSS9  = GND
  DQ13_A  = M_C_CPU1_SA_DQ<13>
  VSS10  = GND
  DQ16_A  = M_C_CPU1_SA_DQ<16>
  VSS11  = GND
  DQ17_A  = M_C_CPU1_SA_DQ<17>
  VSS12  = GND
  DQS2_A_T  = M_C_CPU1_SA_DQS_DP<2>
  DQS2_A_C  = M_C_CPU1_SA_DQS_DN<2>
  VSS13  = GND
  DQ20_A  = M_C_CPU1_SA_DQ<20>
  VSS14  = GND
  DQ21_A  = M_C_CPU1_SA_DQ<21>
  VSS15  = GND
  DQ24_A  = M_C_CPU1_SA_DQ<24>
  VSS16  = GND
  DQ25_A  = M_C_CPU1_SA_DQ<25>
  VSS17  = GND
  DQS3_A_T  = M_C_CPU1_SA_DQS_DP<3>
  DQS3_A_C  = M_C_CPU1_SA_DQS_DN<3>
  VSS18  = GND
  DQ28_A  = M_C_CPU1_SA_DQ<28>
  VSS19  = GND
  DQ29_A  = M_C_CPU1_SA_DQ<29>
  VSS20  = GND
  CB0_A  = M_C_CPU1_SA_CB<0>
  VSS21  = GND
  CB1_A  = M_C_CPU1_SA_CB<1>
  VSS22  = GND
  DQS4_A_T  = M_C_CPU1_SA_DQS_DP<4>
  DQS4_A_C  = M_C_CPU1_SA_DQS_DN<4>
  VSS23  = GND
  CB4_A  = M_C_CPU1_SA_CB<4>
  VSS24  = GND
  CB5_A  = M_C_CPU1_SA_CB<5>
  VSS25  = GND
  ALERT_N  = M_C_CPU1_ALERT_N
  VSS26  = GND
  CS0_A_N  = M_C_CPU1_SA_CS_N<0>
  VSS27  = GND
  CA0_A  = M_C_CPU1_SA_CA<0>
  VSS28  = GND
  CA2_A  = M_C_CPU1_SA_CA<2>
  VSS29  = GND
  CA4_A  = M_C_CPU1_SA_CA<4>
  VSS30  = GND
  CA6_A  = M_C_CPU1_SA_CA<6>
  VSS31  = GND
  PAR_A  = M_C_CPU1_SA_PAR
  VSS32  = GND
  CA0_B  = M_C_CPU1_SB_CA<0>
  VSS33  = GND
  CA2_B  = M_C_CPU1_SB_CA<2>
  VSS34  = GND
  CA4_B  = M_C_CPU1_SB_CA<4>
  VSS35  = GND
  CA6_B  = M_C_CPU1_SB_CA<6>
  VSS36  = GND
  CS0_B_N  = M_C_CPU1_SB_CS_N<0>
  VSS37  = GND
  \lbd||rsp_a_n\  = M_C_CPU1_SA_RSP<0>
  \lbs||rsp_b_n\  = M_C_CPU1_SB_RSP<0>
  VSS38  = GND
  CB4_B  = M_C_CPU1_SB_CB<4>
  VSS39  = GND
  CB5_B  = M_C_CPU1_SB_CB<5>
  VSS40  = GND
  \dqs9_b_t||tdqs9_b_t||dbi4_b_n\  = M_C_CPU1_SB_DQS_DP<9>
  \dqs9_b_c||tdqs9_b_c\  = M_C_CPU1_SB_DQS_DN<9>
  VSS41  = GND
  CB0_B  = M_C_CPU1_SB_CB<0>
  VSS42  = GND
  CB1_B  = M_C_CPU1_SB_CB<1>
  VSS43  = GND
  DQ0_B  = M_C_CPU1_SB_DQ<0>
  VSS44  = GND
  DQ1_B  = M_C_CPU1_SB_DQ<1>
  VSS45  = GND
  DQS0_B_T  = M_C_CPU1_SB_DQS_DP<0>
  DQS0_B_C  = M_C_CPU1_SB_DQS_DN<0>
  VSS46  = GND
  DQ4_B  = M_C_CPU1_SB_DQ<4>
  VSS47  = GND
  DQ5_B  = M_C_CPU1_SB_DQ<5>
  VSS48  = GND
  DQ8_B  = M_C_CPU1_SB_DQ<8>
  VSS49  = GND
  DQ9_B  = M_C_CPU1_SB_DQ<9>
  VSS50  = GND
  DQS1_B_T  = M_C_CPU1_SB_DQS_DP<1>
  DQS1_B_C  = M_C_CPU1_SB_DQS_DN<1>
  VSS51  = GND
  DQ12_B  = M_C_CPU1_SB_DQ<12>
  VSS52  = GND
  DQ13_B  = M_C_CPU1_SB_DQ<13>
  VSS53  = GND
  DQ16_B  = M_C_CPU1_SB_DQ<16>
  VSS54  = GND
  DQ17_B  = M_C_CPU1_SB_DQ<17>
  VSS55  = GND
  DQS2_B_T  = M_C_CPU1_SB_DQS_DP<2>
  DQS2_B_C  = M_C_CPU1_SB_DQS_DN<2>
  VSS56  = GND
  DQ20_B  = M_C_CPU1_SB_DQ<20>
  VSS57  = GND
  DQ21_B  = M_C_CPU1_SB_DQ<21>
  VSS58  = GND
  DQ24_B  = M_C_CPU1_SB_DQ<24>
  VSS59  = GND
  DQ25_B  = M_C_CPU1_SB_DQ<25>
  VSS60  = GND
  DQS3_B_T  = M_C_CPU1_SB_DQS_DP<3>
  DQS3_B_C  = M_C_CPU1_SB_DQS_DN<3>
  VSS61  = GND
  DQ28_B  = M_C_CPU1_SB_DQ<28>
  VSS62  = GND
  DQ29_B  = M_C_CPU1_SB_DQ<29>
  VSS63  = GND
  RFU1  = NC
  VIN_BULK1  = P12V_MEM_CPU1
  VIN_BULK2  = P12V_MEM_CPU1
  \pwr_good||fail_n\  = PWRGD_CHC_CPU1_DIMM
  HAS  = PD_CHC_CPU1_DIMM_SAA
  RFU2  = NC
  RFU3  = NC
  VSS64  = GND
  DQ2_A  = M_C_CPU1_SA_DQ<2>
  VSS65  = GND
  DQ3_A  = M_C_CPU1_SA_DQ<3>
  VSS66  = GND
  \dqs5_a_c||tdqs5_a_c||dqs5_a_t||tdqs5_a_t\  = M_C_CPU1_SA_DQS_DN<5>
  \dqs5_a_t||tdqs5_a_t\  = M_C_CPU1_SA_DQS_DP<5>
  VSS67  = GND
  DQ6_A  = M_C_CPU1_SA_DQ<6>
  VSS68  = GND
  DQ7_A  = M_C_CPU1_SA_DQ<7>
  VSS69  = GND
  DQ10_A  = M_C_CPU1_SA_DQ<10>
  VSS70  = GND
  DQ11_A  = M_C_CPU1_SA_DQ<11>
  VSS71  = GND
  \dqs6_a_c||tdqs6_a_c||dqs6_a_t||tdqs6_a_t\  = M_C_CPU1_SA_DQS_DN<6>
  \dqs6_a_t||tdqs6_a_t\  = M_C_CPU1_SA_DQS_DP<6>
  VSS72  = GND
  DQ14_A  = M_C_CPU1_SA_DQ<14>
  VSS73  = GND
  DQ15_A  = M_C_CPU1_SA_DQ<15>
  VSS74  = GND
  DQ18_A  = M_C_CPU1_SA_DQ<18>
  VSS75  = GND
  DQ19_A  = M_C_CPU1_SA_DQ<19>
  VSS76  = GND
  \dqs7_a_c||tdqs7_a_c\  = M_C_CPU1_SA_DQS_DN<7>
  \dqs7_a_t||tdqs7_a_t\  = M_C_CPU1_SA_DQS_DP<7>
  VSS77  = GND
  DQ22_A  = M_C_CPU1_SA_DQ<22>
  VSS78  = GND
  DQ23_A  = M_C_CPU1_SA_DQ<23>
  VSS79  = GND
  DQ26_A  = M_C_CPU1_SA_DQ<26>
  VSS80  = GND
  DQ27_A  = M_C_CPU1_SA_DQ<27>
  VSS81  = GND
  \dqs8_a_c||tdqs8_a_c\  = M_C_CPU1_SA_DQS_DN<8>
  \dqs8_a_t||tdqs8_a_t\  = M_C_CPU1_SA_DQS_DP<8>
  VSS82  = GND
  DQ30_A  = M_C_CPU1_SA_DQ<30>
  VSS83  = GND
  DQ31_A  = M_C_CPU1_SA_DQ<31>
  VSS84  = GND
  CB2_A  = M_C_CPU1_SA_CB<2>
  VSS85  = GND
  CB3_A  = M_C_CPU1_SA_CB<3>
  VSS86  = GND
  \dqs9_a_c||tdqs9_a_c\  = M_C_CPU1_SA_DQS_DN<9>
  \dqs9_a_t||tdqs9_a_t\  = M_C_CPU1_SA_DQS_DP<9>
  VSS87  = GND
  CB6_A  = M_C_CPU1_SA_CB<6>
  VSS88  = GND
  CB7_A  = M_C_CPU1_SA_CB<7>
  VSS89  = GND
  RESET_N  = M_C_CPU1_RESET_N
  VSS90  = GND
  CS1_A_N  = M_C_CPU1_SA_CS_N<1>
  VSS91  = GND
  CA1_A  = M_C_CPU1_SA_CA<1>
  VSS92  = GND
  CA3_A  = M_C_CPU1_SA_CA<3>
  VSS93  = GND
  CA5_A  = M_C_CPU1_SA_CA<5>
  VSS94  = GND
  CK_T  = M_C_CPU1_CLK_DP<0>
  CK_C  = M_C_CPU1_CLK_DN<0>
  VSS95  = GND
  RFU4  = NC
  CA1_B  = M_C_CPU1_SB_CA<1>
  VSS96  = GND
  CA3_B  = M_C_CPU1_SB_CA<3>
  VSS97  = GND
  CA5_B  = M_C_CPU1_SB_CA<5>
  VSS98  = GND
  PAR_B  = M_C_CPU1_SB_PAR
  VSS99  = GND
  CS1_B_N  = M_C_CPU1_SB_CS_N<1>
  VSS100  = GND
  RFU5  = NC
  RFU6  = NC
  VSS101  = GND
  CB6_B  = M_C_CPU1_SB_CB<6>
  VSS102  = GND
  CB7_B  = M_C_CPU1_SB_CB<7>
  VSS103  = GND
  DQS4_B_C  = M_C_CPU1_SB_DQS_DN<4>
  DQS4_B_T  = M_C_CPU1_SB_DQS_DP<4>
  VSS104  = GND
  CB2_B  = M_C_CPU1_SB_CB<2>
  VSS105  = GND
  CB3_B  = M_C_CPU1_SB_CB<3>
  VSS106  = GND
  DQ2_B  = M_C_CPU1_SB_DQ<2>
  VSS107  = GND
  DQ3_B  = M_C_CPU1_SB_DQ<3>
  VSS108  = GND
  \dqs5_b_c||tdqs5_b_c\  = M_C_CPU1_SB_DQS_DN<5>
  \dqs5_b_t||tdqs5_b_t\  = M_C_CPU1_SB_DQS_DP<5>
  VSS109  = GND
  DQ6_B  = M_C_CPU1_SB_DQ<6>
  VSS110  = GND
  DQ7_B  = M_C_CPU1_SB_DQ<7>
  VSS111  = GND
  DQ10_B  = M_C_CPU1_SB_DQ<10>
  VSS112  = GND
  DQ11_B  = M_C_CPU1_SB_DQ<11>
  VSS113  = GND
  \dqs6_b_c||tdqs6_b_c\  = M_C_CPU1_SB_DQS_DN<6>
  \dqs6_b_t||tdqs6_b_t\  = M_C_CPU1_SB_DQS_DP<6>
  VSS114  = GND
  DQ14_B  = M_C_CPU1_SB_DQ<14>
  VSS115  = GND
  DQ15_B  = M_C_CPU1_SB_DQ<15>
  VSS116  = GND
  DQ18_B  = M_C_CPU1_SB_DQ<18>
  VSS117  = GND
  DQ19_B  = M_C_CPU1_SB_DQ<19>
  VSS118  = GND
  \dqs7_b_c||tdqs7_b_c\  = M_C_CPU1_SB_DQS_DN<7>
  \dqs7_b_t||tdqs7_b_t\  = M_C_CPU1_SB_DQS_DP<7>
  VSS119  = GND
  DQ22_B  = M_C_CPU1_SB_DQ<22>
  VSS120  = GND
  DQ23_B  = M_C_CPU1_SB_DQ<23>
  VSS121  = GND
  DQ26_B  = M_C_CPU1_SB_DQ<26>
  VSS122  = GND
  DQ27_B  = M_C_CPU1_SB_DQ<27>
  VSS123  = GND
  \dqs8_b_c||tdqs8_b_c\  = M_C_CPU1_SB_DQS_DN<8>
  \dqs8_b_t||tdqs8_b_t\  = M_C_CPU1_SB_DQS_DP<8>
  VSS124  = GND
  DQ30_B  = M_C_CPU1_SB_DQ<30>
  VSS125  = GND
  DQ31_B  = M_C_CPU1_SB_DQ<31>
  VSS126  = GND
  G1  = GND
  G2  = GND
  G3  = GND

(kicad_pcb
	(version 20260206)
	(generator "pcbnew")
	(generator_version "10.0")
	(general
		(thickness 1.6)
		(legacy_teardrops no)
	)
	(paper "A4")
	(title_block
		(title "04192023_DAF0TMB3IC0_F0TG_MB_C_brd_V02_OCP.brd")
		(comment 1 "Grand Teton / footprint 4188 of 8354 (J28), pads 185-230 of 291")
	)
	(layers
		(0 "F.Cu" signal "TOP")
		(4 "In1.Cu" signal "GND")
		(6 "In2.Cu" signal "IN1")
		(8 "In3.Cu" signal "GND1")
		(10 "In4.Cu" signal "IN2")
		(12 "In5.Cu" signal "GND2")
		(14 "In6.Cu" signal "IN3")
		(16 "In7.Cu" signal "GND3")
		(18 "In8.Cu" signal "VCC")
		(20 "In9.Cu" signal "VCC1")
		(22 "In10.Cu" signal "GND4")
		(24 "In11.Cu" signal "IN4")
		(26 "In12.Cu" signal "GND5")
		(28 "In13.Cu" signal "IN5")
		(30 "In14.Cu" signal "GND6")
		(32 "In15.Cu" signal "IN6")
		(34 "In16.Cu" signal "GND7")
		(2 "B.Cu" signal "BOTTOM")
		(9 "F.Adhes" user "F.Adhesive")
		(11 "B.Adhes" user "B.Adhesive")
		(13 "F.Paste" user "Package Geometry/Pastemask Top")
		(15 "B.Paste" user "Package Geometry/Pastemask Bottom")
		(5 "F.SilkS" user "Ref Des/Silkscreen Top")
		(7 "B.SilkS" user "Ref Des/Silkscreen Bottom")
		(1 "F.Mask" user "Board Geometry/Soldermask Top")
		(3 "B.Mask" user "Board Geometry/Soldermask Bottom")
		(17 "Dwgs.User" user "User.Drawings")
		(19 "Cmts.User" user "User.Comments")
		(21 "Eco1.User" user "User.Eco1")
		(23 "Eco2.User" user "User.Eco2")
		(25 "Edge.Cuts" user "Board Geometry/Outline")
		(27 "Margin" user)
		(31 "F.CrtYd" user "Package Geometry/Place Bound Top")
		(29 "B.CrtYd" user "Package Geometry/Place Bound Bottom")
		(35 "F.Fab" user "Ref Des/Assembly Top")
		(33 "B.Fab" user "Ref Des/Assembly Bottom")
	)
	(footprint ""
		(layer "F.Cu")
		(at 42.289984 -255.560322 180)
		(property "Reference" "J28"
			(at -2.876296 -82.230976 0)
			(unlocked yes)
			(layer "F.SilkS")
			(effects
				(font
					(size 0.7874 0.5842)
					(thickness 0.1524)
				)
			)
		)
		(property "Value" ""
			(at 0 0 180)
			(layer "F.Fab")
			(effects
				(font
					(size 1.27 1.27)
				)
			)
		)
		(duplicate_pad_numbers_are_jumpers no)
		(pad "185" smd rect
			(at 2.050034 -29.325062 90)
			(size 0.519938 1.4986)
			(layers "F.Cu" "F.Mask" "F.Paste")
			(net "M_C_CPU1_SA_DQ<26>")
		)
		(pad "186" smd rect
			(at 2.050034 -28.474924 90)
			(size 0.519938 1.4986)
			(layers "F.Cu" "F.Mask" "F.Paste")
			(net "GND")
		)
		(pad "187" smd rect
			(at 2.050034 -27.62504 90)
			(size 0.519938 1.4986)
			(layers "F.Cu" "F.Mask" "F.Paste")
			(net "M_C_CPU1_SA_DQ<27>")
		)
		(pad "188" smd rect
			(at 2.050034 -26.774902 90)
			(size 0.519938 1.4986)
			(layers "F.Cu" "F.Mask" "F.Paste")
			(net "GND")
		)
		(pad "189" smd rect
			(at 2.050034 -25.925018 90)
			(size 0.519938 1.4986)
			(layers "F.Cu" "F.Mask" "F.Paste")
			(net "M_C_CPU1_SA_DQS_DN<8>")
		)
		(pad "190" smd rect
			(at 2.050034 -25.07488 90)
			(size 0.519938 1.4986)
			(layers "F.Cu" "F.Mask" "F.Paste")
			(net "M_C_CPU1_SA_DQS_DP<8>")
		)
		(pad "191" smd rect
			(at 2.050034 -24.224996 90)
			(size 0.519938 1.4986)
			(layers "F.Cu" "F.Mask" "F.Paste")
			(net "GND")
		)
		(pad "192" smd rect
			(at 2.050034 -23.375112 90)
			(size 0.519938 1.4986)
			(layers "F.Cu" "F.Mask" "F.Paste")
			(net "M_C_CPU1_SA_DQ<30>")
		)
		(pad "193" smd rect
			(at 2.050034 -22.524974 90)
			(size 0.519938 1.4986)
			(layers "F.Cu" "F.Mask" "F.Paste")
			(net "GND")
		)
		(pad "194" smd rect
			(at 2.050034 -21.67509 90)
			(size 0.519938 1.4986)
			(layers "F.Cu" "F.Mask" "F.Paste")
			(net "M_C_CPU1_SA_DQ<31>")
		)
		(pad "195" smd rect
			(at 2.050034 -20.824952 90)
			(size 0.519938 1.4986)
			(layers "F.Cu" "F.Mask" "F.Paste")
			(net "GND")
		)
		(pad "196" smd rect
			(at 2.050034 -19.975068 90)
			(size 0.519938 1.4986)
			(layers "F.Cu" "F.Mask" "F.Paste")
			(net "M_C_CPU1_SA_CB<2>")
		)
		(pad "197" smd rect
			(at 2.050034 -19.12493 90)
			(size 0.519938 1.4986)
			(layers "F.Cu" "F.Mask" "F.Paste")
			(net "GND")
		)
		(pad "198" smd rect
			(at 2.050034 -18.275046 90)
			(size 0.519938 1.4986)
			(layers "F.Cu" "F.Mask" "F.Paste")
			(net "M_C_CPU1_SA_CB<3>")
		)
		(pad "199" smd rect
			(at 2.050034 -17.424908 90)
			(size 0.519938 1.4986)
			(layers "F.Cu" "F.Mask" "F.Paste")
			(net "GND")
		)
		(pad "200" smd rect
			(at 2.050034 -16.575024 90)
			(size 0.519938 1.4986)
			(layers "F.Cu" "F.Mask" "F.Paste")
			(net "M_C_CPU1_SA_DQS_DN<9>")
		)
		(pad "201" smd rect
			(at 2.050034 -15.724886 90)
			(size 0.519938 1.4986)
			(layers "F.Cu" "F.Mask" "F.Paste")
			(net "M_C_CPU1_SA_DQS_DP<9>")
		)
		(pad "202" smd rect
			(at 2.050034 -14.875002 90)
			(size 0.519938 1.4986)
			(layers "F.Cu" "F.Mask" "F.Paste")
			(net "GND")
		)
		(pad "203" smd rect
			(at 2.050034 -14.025118 90)
			(size 0.519938 1.4986)
			(layers "F.Cu" "F.Mask" "F.Paste")
			(net "M_C_CPU1_SA_CB<6>")
		)
		(pad "204" smd rect
			(at 2.050034 -13.17498 90)
			(size 0.519938 1.4986)
			(layers "F.Cu" "F.Mask" "F.Paste")
			(net "GND")
		)
		(pad "205" smd rect
			(at 2.050034 -12.325096 90)
			(size 0.519938 1.4986)
			(layers "F.Cu" "F.Mask" "F.Paste")
			(net "M_C_CPU1_SA_CB<7>")
		)
		(pad "206" smd rect
			(at 2.050034 -11.474958 90)
			(size 0.519938 1.4986)
			(layers "F.Cu" "F.Mask" "F.Paste")
			(net "GND")
		)
		(pad "207" smd rect
			(at 2.050034 -10.625074 90)
			(size 0.519938 1.4986)
			(layers "F.Cu" "F.Mask" "F.Paste")
			(net "M_C_CPU1_RESET_N")
		)
		(pad "208" smd rect
			(at 2.050034 -9.774936 90)
			(size 0.519938 1.4986)
			(layers "F.Cu" "F.Mask" "F.Paste")
			(net "GND")
		)
		(pad "209" smd rect
			(at 2.050034 -8.925052 90)
			(size 0.519938 1.4986)
			(layers "F.Cu" "F.Mask" "F.Paste")
			(net "M_C_CPU1_SA_CS_N<1>")
		)
		(pad "210" smd rect
			(at 2.050034 -8.074914 90)
			(size 0.519938 1.4986)
			(layers "F.Cu" "F.Mask" "F.Paste")
			(net "GND")
		)
		(pad "211" smd rect
			(at 2.050034 -7.22503 90)
			(size 0.519938 1.4986)
			(layers "F.Cu" "F.Mask" "F.Paste")
			(net "M_C_CPU1_SA_CA<1>")
		)
		(pad "212" smd rect
			(at 2.050034 -6.374892 90)
			(size 0.519938 1.4986)
			(layers "F.Cu" "F.Mask" "F.Paste")
			(net "GND")
		)
		(pad "213" smd rect
			(at 2.050034 -5.525008 90)
			(size 0.519938 1.4986)
			(layers "F.Cu" "F.Mask" "F.Paste")
			(net "M_C_CPU1_SA_CA<3>")
		)
		(pad "214" smd rect
			(at 2.050034 -4.675124 90)
			(size 0.519938 1.4986)
			(layers "F.Cu" "F.Mask" "F.Paste")
			(net "GND")
		)
		(pad "215" smd rect
			(at 2.050034 -3.824986 90)
			(size 0.519938 1.4986)
			(layers "F.Cu" "F.Mask" "F.Paste")
			(net "M_C_CPU1_SA_CA<5>")
		)
		(pad "216" smd rect
			(at 2.050034 -2.975102 90)
			(size 0.519938 1.4986)
			(layers "F.Cu" "F.Mask" "F.Paste")
			(net "GND")
		)
		(pad "217" smd rect
			(at 2.050034 -2.124964 90)
			(size 0.519938 1.4986)
			(layers "F.Cu" "F.Mask" "F.Paste")
			(net "M_C_CPU1_CLK_DP<0>")
		)
		(pad "218" smd rect
			(at 2.050034 -1.27508 90)
			(size 0.519938 1.4986)
			(layers "F.Cu" "F.Mask" "F.Paste")
			(net "M_C_CPU1_CLK_DN<0>")
		)
		(pad "219" smd rect
			(at 2.050034 -0.424942 90)
			(size 0.519938 1.4986)
			(layers "F.Cu" "F.Mask" "F.Paste")
			(net "GND")
		)
		(pad "220" smd rect
			(at 2.050034 5.525008 90)
			(size 0.519938 1.4986)
			(layers "F.Cu" "F.Mask" "F.Paste")
			(net "Net_2288")
		)
		(pad "221" smd rect
			(at 2.050034 6.374892 90)
			(size 0.519938 1.4986)
			(layers "F.Cu" "F.Mask" "F.Paste")
			(net "M_C_CPU1_SB_CA<1>")
		)
		(pad "222" smd rect
			(at 2.050034 7.22503 90)
			(size 0.519938 1.4986)
			(layers "F.Cu" "F.Mask" "F.Paste")
			(net "GND")
		)
		(pad "223" smd rect
			(at 2.050034 8.074914 90)
			(size 0.519938 1.4986)
			(layers "F.Cu" "F.Mask" "F.Paste")
			(net "M_C_CPU1_SB_CA<3>")
		)
		(pad "224" smd rect
			(at 2.050034 8.925052 90)
			(size 0.519938 1.4986)
			(layers "F.Cu" "F.Mask" "F.Paste")
			(net "GND")
		)
		(pad "225" smd rect
			(at 2.050034 9.774936 90)
			(size 0.519938 1.4986)
			(layers "F.Cu" "F.Mask" "F.Paste")
			(net "M_C_CPU1_SB_CA<5>")
		)
		(pad "226" smd rect
			(at 2.050034 10.625074 90)
			(size 0.519938 1.4986)
			(layers "F.Cu" "F.Mask" "F.Paste")
			(net "GND")
		)
		(pad "227" smd rect
			(at 2.050034 11.474958 90)
			(size 0.519938 1.4986)
			(layers "F.Cu" "F.Mask" "F.Paste")
			(net "M_C_CPU1_SB_PAR")
		)
		(pad "228" smd rect
			(at 2.050034 12.325096 90)
			(size 0.519938 1.4986)
			(layers "F.Cu" "F.Mask" "F.Paste")
			(net "GND")
		)
		(pad "229" smd rect
			(at 2.050034 13.17498 90)
			(size 0.519938 1.4986)
			(layers "F.Cu" "F.Mask" "F.Paste")
			(net "M_C_CPU1_SB_CS_N<1>")
		)
		(pad "230" smd rect
			(at 2.050034 14.025118 90)
			(size 0.519938 1.4986)
			(layers "F.Cu" "F.Mask" "F.Paste")
			(net "GND")
		)
	)
)
